FILE_TYPE = CONNECTIVITY;
{Allegro Design Entry HDL 16.6-p007 (v16-6-112F) 10/10/2012}
"PAGE_NUMBER" = 237;
0"NC";
1"GND\g";
2"GND\g";
3"GND\g";
4"P1V8_PCH_STBY\g";
5"GND\g";
6"P3V3_STBY\g";
7"GND\g"VOLTAGE"0 V";
8"P3V3_STBY\g";
9"GND\g";
10"GND\g"VOLTAGE"0V";
11"PWRGD_P1V8_PCH_STBY";
12"PWRGD_P1V8_PCH_STBY_R";
13"PWRGD_P3V3_STBY";
14"VR_P1V8_PCH_STBY_FB";
%"CAP"
"1","(3375,2150)","0","mstr_discrete","I12";
;
TOLERANCE"20%"
VOLTAGE"6.3V"
MATERIAL"X6S"
VALUE"22UF"
LOCATION"C2L45"
PART_NUMBER"C95333-008"
PACK_TYPE"0805"
CDS_SEC"1"
$SEC"1"
ROOM"P1V8_PCH_STBY_VR"
BOM_COST"P1V8_PCH_STBY_VR"
CDS_LOCATION"C2L45"
CDS_LIB"mstr_discrete";
"A"
$PN"1"4;
"B"
$PN"2"1;
%"CAP"
"1","(3100,2200)","0","mstr_discrete","I13";
;
CDS_SEC"1"
PART_NUMBER"C95333-008"
LOCATION"C8A14"
MATERIAL"X6S"
VOLTAGE"6.3V"
TOLERANCE"20%"
VALUE"22UF"
PACK_TYPE"0805"
SEC"1"
ROOM"P1V8_PCH_STBY_VR"
BOM_COST"P1V8_PCH_STBY_VR"
SEC_TYPE"0805"
CDS_LOCATION"C8A14"
CDS_LIB"mstr_discrete";
"A"
$PN"1"4;
"B"
$PN"2"1;
%"GND"
"1","(3500,1400)","0","mstr_symbols","I14";
;
BOM_COST"P1V8_PCH_STBY_VR"
SIZE"1B"
CDS_LIB"mstr_symbols"
VOLTAGE"0.0V"
ROOM"P1V8_PCH_STBY_VR"
BODY_TYPE"PLUMBING"
HDL_POWER"GND";
"A\NAC"1;
%"RES"
"2","(2800,2125)","0","mstr_discrete","I15";
;
CDS_SEC"1"
LOCATION"R8A12"
VALUE"475.0"
TOLERANCE"1%"
MATERIAL"CHIP"
WATTAGE"1/10W"
PART_NUMBER"G22026-030"
PACK_TYPE"0603"
SEC_TYPE"0603"
BOM_COST"P1V8_PCH_STBY_VR"
SEC"1"
CDS_LOCATION"R8A12"
ROOM"P1V8_PCH_STBY_VR"
CDS_LIB"mstr_discrete";
"A"
$PN"1"4;
"B"
$PN"2"1;
%"CAP"
"1","(-1975,3150)","0","mstr_discrete","I29";
;
CDS_SEC"1"
VOLTAGE"6.3V"
TOLERANCE"20%"
VALUE"10UF"
LOCATION"C8A6"
MATERIAL"X6S"
PACK_TYPE"0603"
PART_NUMBER"E15431-002"
SEC_TYPE"0603"
SEC"1"
BOM_COST"P1V8_PCH_STBY_VR"
ROOM"P1V8_PCH_STBY_VR"
CDS_LOCATION"C8A6"
CDS_LIB"mstr_discrete";
"A"
$PN"1"8;
"B"
$PN"2"2;
%"RES"
"2","(1350,3875)","0","mstr_discrete","I3";
;
LOCATION"R8A10"
PART_NUMBER"G21796-140"
VALUE"5.11K"
WATTAGE"1/16W"
TOLERANCE"1%"
PACK_TYPE"0402"
MATERIAL"CHIP"
CDS_SEC"1"
$SEC"1"
BOM_COST"P1V8_PCH_STBY_VR"
ROOM"P1V8_PCH_STBY_VR"
CDS_LOCATION"R8A10"
CDS_LIB"mstr_discrete";
"A"
$PN"1"6;
"B"
$PN"2"12;
%"GND"
"1","(-1975,2800)","0","mstr_symbols","I30";
;
CDS_LIB"mstr_symbols"
SIZE"1B"
VOLTAGE"0.0V"
BOM_COST"P1V8_PCH_STBY_VR"
ROOM"P1V8_PCH_STBY_VR"
BODY_TYPE"PLUMBING"
HDL_POWER"GND";
"A\NAC"2;
%"CAP"
"1","(-1550,3175)","0","mstr_discrete","I31";
;
CDS_SEC"1"
PART_NUMBER"602433-020"
LOCATION"C8A4"
VALUE"0.1UF"
TOLERANCE"10%"
VOLTAGE"25V"
MATERIAL"X7R"
PACK_TYPE"0603LF"
BOM_COST"P1V8_PCH_STBY_VR"
SEC_TYPE"0603LF"
SEC"1"
CDS_LOCATION"C8A4"
ROOM"P1V8_PCH_STBY_VR"
CDS_LIB"mstr_discrete";
"A"
$PN"1"8;
"B"
$PN"2"3;
%"GND"
"1","(-1550,2775)","0","mstr_symbols","I32";
;
SIZE"1B"
CDS_LIB"mstr_symbols"
VOLTAGE"0.0V"
BOM_COST"P1V8_PCH_STBY_VR"
ROOM"P1V8_PCH_STBY_VR"
BODY_TYPE"PLUMBING"
HDL_POWER"GND";
"A\NAC"3;
%"P1V8_PCH_STBY"
"1","(3925,2850)","0","mstr_symbols","I4";
;
CDS_LIB"mstr_symbols"
BOM_COST"P1V8_PCH_STBY_VR"
ROOM"P1V8_PCH_STBY_VR"
VOLTAGE"1.8V"
BODY_TYPE"PLUMBING"
HDL_POWER"P1V8_PCH_STBY";
"G\NAC"4;
%"CAP"
"1","(1350,3475)","0","mstr_discrete","I5";
;
LOCATION"C8A11"
PART_NUMBER"A36096-046"
VALUE"1000PF"
PACK_TYPE"0402LF"
TOLERANCE"10%"
VOLTAGE"50V"
MATERIAL"X7R"
$SEC"1"
ROOM"P1V8_PCH_STBY_VR"
BOM_COST"P1V8_PCH_STBY_VR"
CDS_SEC"1"
CDS_LOCATION"C8A11"
CDS_LIB"mstr_discrete";
"A"
$PN"1"12;
"B"
$PN"2"5;
%"CAP"
"1","(-1500,2200)","2","mstr_discrete","I55";
;
PACK_TYPE"0402LF"
VOLTAGE"50V"
TOLERANCE"10%"
MATERIAL"EMPTY"
LOCATION"C8A10"
VALUE"1000PF"
PART_NUMBER"A36096-046"
CDS_LIB"mstr_discrete"
BOM_COST"P1V8_PCH_STBY_VR"
CDS_SEC"1"
$SEC"1"
ROOM"P1V8_PCH_STBY_VR"
CDS_LOCATION"C8A10";
"A"
$PN"1"13;
"B"
$PN"2"10;
%"GND"
"1","(1350,3150)","0","mstr_symbols","I6";
;
SIZE"1B"
VOLTAGE"0.0V"
CDS_LIB"mstr_symbols"
BOM_COST"P1V8_PCH_STBY_VR"
ROOM"P1V8_PCH_STBY_VR"
BODY_TYPE"PLUMBING"
HDL_POWER"GND";
"A\NAC"5;
%"P3V3_STBY"
"1","(1350,4125)","0","mstr_symbols","I65";
;
SIZE"1B"
CDS_LIB"mstr_symbols"
VOLTAGE"3.3V"
BODY_TYPE"PLUMBING"
HDL_POWER"P3V3_STBY";
"G\NAC"6;
%"GND"
"1","(525,2300)","0","mstr_symbols","I71";
;
CDS_LIB"mstr_symbols"
SIZE"1B"
VOLTAGE"0.0V"
BOM_COST"P1V8_PCH_STBY_VR"
ROOM"P1V8_PCH_STBY_VR"
BODY_TYPE"PLUMBING"
HDL_POWER"GND";
"A\NAC"7;
%"CAP"
"1","(3650,2200)","0","mstr_discrete","I77";
;
CDS_SEC"1"
PART_NUMBER"C95333-006"
LOCATION"C8A12"
TOLERANCE"20%"
VOLTAGE"4V"
MATERIAL"X6S"
VALUE"47UF"
PACK_TYPE"0805"
SEC_TYPE"0805"
SEC"1"
ROOM"P1V8_PCH_STBY_VR"
CDS_LOCATION"C8A12"
CDS_LIB"mstr_discrete";
"A"
$PN"1"4;
"B"
$PN"2"1;
%"CAP"
"1","(3900,1850)","0","mstr_discrete","I79";
;
CDS_SEC"1"
PART_NUMBER"C95333-006"
VOLTAGE"4V"
TOLERANCE"20%"
VALUE"47UF"
LOCATION"C2L32"
PACK_TYPE"0805"
MATERIAL"X6S"
SEC_TYPE"0805"
SEC"1"
ROOM"P1V8_PCH_STBY_VR"
CDS_LOCATION"C2L32"
CDS_LIB"mstr_discrete";
"A"
$PN"1"4;
"B"
$PN"2"1;
%"RES"
"2","(2325,1700)","0","mstr_discrete","I80";
;
CDS_SEC"1"
MATERIAL"CHIP"
PART_NUMBER"G21796-048"
LOCATION"R2L19"
VALUE"49.9K"
WATTAGE"1/16W"
TOLERANCE"1%"
PACK_TYPE"0402"
ROOM"P1V8_PCH_STBY_VR"
SEC_TYPE"0402"
SEC"1"
CDS_LOCATION"R2L19"
CDS_LIB"mstr_discrete";
"A"
$PN"1"14;
"B"
$PN"2"9;
%"RES"
"2","(2325,2275)","0","mstr_discrete","I81";
;
CDS_SEC"1"
PART_NUMBER"G21796-327"
VALUE"63.4K"
LOCATION"R2L20"
TOLERANCE"1.0%"
WATTAGE"1/16W"
PACK_TYPE"0402"
MATERIAL"CHIP"
CDS_LOCATION"R2L20"
SEC"1"
ROOM"P1V8_PCH_STBY_VR"
SEC_TYPE"0402"
CDS_LIB"mstr_discrete";
"A"
$PN"1"4;
"B"
$PN"2"14;
%"P3V3_STBY"
"1","(-1750,3650)","0","mstr_symbols","I85";
;
VOLTAGE"3.3V"
CDS_LIB"mstr_symbols"
SIZE"1B"
BODY_TYPE"PLUMBING"
HDL_POWER"P3V3_STBY";
"G\NAC"8;
%"RT9059"
"1","(-50,2725)","0","mstr_vreg","I86";
;
CDS_SEC"1"
LOCATION"EU8A2"
MATERIAL"IC"
PART_NUMBER"H65765-001"
PACK_TYPE"DFN"
SEC_TYPE"DFN"
SEC"1"
CDS_LOCATION"EU8A2"
ROOM"P1V8_PCH_STBY_VR"
CDS_LIB"mstr_vreg";
"VIN<0>"
$PN"7"8;
"VIN<1>"
$PN"8"8;
"VIN<2>"
$PN"9"8;
"EN"
$PN"6"13;
"VOUT<0>"
$PN"1"4;
"VOUT<1>"
$PN"2"4;
"VOUT<2>"
$PN"3"4;
"GND"
$PN"11"7;
"ADJ_NC"
$PN"4"14;
"VDD"
$PN"10"8;
"PGOOD"
$PN"5"12;
%"RES"
"1","(2175,3650)","0","mstr_discrete","I90";
;
CDS_SEC"1"
PART_NUMBER"G21796-250"
LOCATION"R8A11"
TOLERANCE"1.0%"
PACK_TYPE"0402"
MATERIAL"CHIP"
VALUE"22.1"
WATTAGE"1/16W"
ROOM"P1V8_PCH_STBY_VR"
SEC"1"
SEC_TYPE"0402"
CDS_LIB"mstr_discrete"
CDS_LOCATION"R8A11";
"B"
$PN"2"11;
"A"
$PN"1"12;
%"GND"
"1","(2325,1425)","0","mstr_symbols","I91";
;
VOLTAGE"0.0V"
SIZE"1B"
CDS_LIB"mstr_symbols"
ROOM"P1V8_PCH_STBY_VR"
BOM_COST"P1V8_PCH_STBY_VR"
BODY_TYPE"PLUMBING"
HDL_POWER"GND";
"A\NAC"9;
%"GND"
"1","(-1500,1950)","0","mstr_symbols","I92";
;
BOM_COST"P1V8_PCH_STBY_VR"
VOLTAGE"0.0V"
SIZE"1B"
CDS_LIB"mstr_symbols"
ROOM"P1V8_PCH_STBY_VR"
BODY_TYPE"PLUMBING"
HDL_POWER"GND";
"A\NAC"10;
END.
